# S9S_MB_2U (Grand Teton) — schematic netlist excerpt (pin names and nets, part order shuffled) for the footprints in the layout excerpt that follows; sources: Cadence DE-HDL packaged netlist, KiCad conversion of 03242023_DA0F0TMBIJ0_F0T_Motherboard_J_brd_V01_OCP.brd

R1810  Q_RES  1K 1% EMPTY  pkg 0402LF  page 198 : A = FM_ADR_MODE0 ; B = GND
PR4000  Q_RES  160K 1% EMPTY  pkg 0402LF  page 242 : A = P12V_AUX ; B = P12V_SCM_UV

(kicad_pcb
	(version 20260206)
	(generator "pcbnew")
	(generator_version "10.0")
	(general
		(thickness 1.6)
		(legacy_teardrops no)
	)
	(paper "A4")
	(title_block
		(title "03242023_DA0F0TMBIJ0_F0T_Motherboard_J_brd_V01_OCP.brd")
		(comment 1 "Grand Teton / footprints 3790-3791 of 6105")
	)
	(layers
		(0 "F.Cu" signal "TOP")
		(4 "In1.Cu" signal "GND")
		(6 "In2.Cu" signal "IN1")
		(8 "In3.Cu" signal "GND1")
		(10 "In4.Cu" signal "IN2")
		(12 "In5.Cu" signal "GND2")
		(14 "In6.Cu" signal "IN3")
		(16 "In7.Cu" signal "GND3")
		(18 "In8.Cu" signal "VCC")
		(20 "In9.Cu" signal "VCC1")
		(22 "In10.Cu" signal "GND4")
		(24 "In11.Cu" signal "IN4")
		(26 "In12.Cu" signal "GND5")
		(28 "In13.Cu" signal "IN5")
		(30 "In14.Cu" signal "GND6")
		(32 "In15.Cu" signal "IN6")
		(34 "In16.Cu" signal "GND7")
		(2 "B.Cu" signal "BOTTOM")
		(9 "F.Adhes" user "F.Adhesive")
		(11 "B.Adhes" user "B.Adhesive")
		(13 "F.Paste" user "Package Geometry/Pastemask Top")
		(15 "B.Paste" user "Package Geometry/Pastemask Bottom")
		(5 "F.SilkS" user "Ref Des/Silkscreen Top")
		(7 "B.SilkS" user "Ref Des/Silkscreen Bottom")
		(1 "F.Mask" user "Board Geometry/Soldermask Top")
		(3 "B.Mask" user "Board Geometry/Soldermask Bottom")
		(17 "Dwgs.User" user "User.Drawings")
		(19 "Cmts.User" user "User.Comments")
		(21 "Eco1.User" user "User.Eco1")
		(23 "Eco2.User" user "User.Eco2")
		(25 "Edge.Cuts" user "Board Geometry/Outline")
		(27 "Margin" user)
		(31 "F.CrtYd" user "Package Geometry/Place Bound Top")
		(29 "B.CrtYd" user "Package Geometry/Place Bound Bottom")
		(35 "F.Fab" user "Ref Des/Assembly Top")
		(33 "B.Fab" user "Ref Des/Assembly Bottom")
	)
	(footprint ""
		(layer "F.Cu")
		(at 322.263516 -23.551896 180)
		(property "Reference" "R1810"
			(at 0 0 180)
			(layer "F.SilkS")
			(hide yes)
			(effects
				(font
					(size 1.27 1.27)
				)
			)
		)
		(property "Value" ""
			(at 0 0 180)
			(layer "F.Fab")
			(effects
				(font
					(size 1.27 1.27)
				)
			)
		)
		(duplicate_pad_numbers_are_jumpers no)
		(fp_line
			(start 0.7874 0.4064)
			(end -0.7874 0.4064)
			(stroke
				(width 0.1524)
				(type default)
			)
			(layer "F.SilkS")
		)
		(fp_line
			(start 0.7874 -0.4064)
			(end 0.7874 0.4064)
			(stroke
				(width 0.1524)
				(type default)
			)
			(layer "F.SilkS")
		)
		(fp_line
			(start -0.7874 0.4064)
			(end -0.7874 -0.4064)
			(stroke
				(width 0.1524)
				(type default)
			)
			(layer "F.SilkS")
		)
		(fp_line
			(start -0.7874 -0.4064)
			(end 0.7874 -0.4064)
			(stroke
				(width 0.1524)
				(type default)
			)
			(layer "F.SilkS")
		)
		(fp_line
			(start 0.67945 0.3048)
			(end 0.120396 0.3048)
			(stroke
				(width 0.1)
				(type default)
			)
			(layer "F.Fab")
		)
		(fp_line
			(start 0.67945 -0.3048)
			(end 0.67945 0.3048)
			(stroke
				(width 0.1)
				(type default)
			)
			(layer "F.Fab")
		)
		(fp_line
			(start 0.12065 -0.2794)
			(end 0.12065 -0.3048)
			(stroke
				(width 0.1)
				(type default)
			)
			(layer "F.Fab")
		)
		(fp_line
			(start 0.12065 -0.3048)
			(end 0.67945 -0.3048)
			(stroke
				(width 0.1)
				(type default)
			)
			(layer "F.Fab")
		)
		(fp_line
			(start 0.120396 0.3048)
			(end 0.120396 0.2794)
			(stroke
				(width 0.1)
				(type default)
			)
			(layer "F.Fab")
		)
		(fp_line
			(start 0.120396 0.2794)
			(end -0.12065 0.2794)
			(stroke
				(width 0.1)
				(type default)
			)
			(layer "F.Fab")
		)
		(fp_line
			(start -0.12065 0.3048)
			(end -0.67945 0.3048)
			(stroke
				(width 0.1)
				(type default)
			)
			(layer "F.Fab")
		)
		(fp_line
			(start -0.12065 0.2794)
			(end -0.12065 0.3048)
			(stroke
				(width 0.1)
				(type default)
			)
			(layer "F.Fab")
		)
		(fp_line
			(start -0.12065 -0.2794)
			(end 0.12065 -0.2794)
			(stroke
				(width 0.1)
				(type default)
			)
			(layer "F.Fab")
		)
		(fp_line
			(start -0.12065 -0.305054)
			(end -0.12065 -0.2794)
			(stroke
				(width 0.1)
				(type default)
			)
			(layer "F.Fab")
		)
		(fp_line
			(start -0.67945 0.3048)
			(end -0.67945 -0.305054)
			(stroke
				(width 0.1)
				(type default)
			)
			(layer "F.Fab")
		)
		(fp_line
			(start -0.67945 -0.305054)
			(end -0.12065 -0.305054)
			(stroke
				(width 0.1)
				(type default)
			)
			(layer "F.Fab")
		)
		(pad "1" smd circle
			(at -0.40005 0 180)
			(size 0 0)
			(layers "F.Cu" "F.Mask" "F.Paste")
			(net "FM_ADR_MODE0")
		)
		(pad "2" smd circle
			(at 0.40005 0 180)
			(size 0 0)
			(layers "F.Cu" "F.Mask" "F.Paste")
			(net "GND")
		)
	)
	(footprint ""
		(layer "F.Cu")
		(at 185.799222 -23.113492)
		(property "Reference" "PR4000"
			(at 0 0 0)
			(layer "F.SilkS")
			(hide yes)
			(effects
				(font
					(size 1.27 1.27)
				)
			)
		)
		(property "Value" ""
			(at 0 0 0)
			(layer "F.Fab")
			(effects
				(font
					(size 1.27 1.27)
				)
			)
		)
		(duplicate_pad_numbers_are_jumpers no)
		(fp_line
			(start -0.7874 -0.4064)
			(end 0.7874 -0.4064)
			(stroke
				(width 0.1524)
				(type default)
			)
			(layer "F.SilkS")
		)
		(fp_line
			(start -0.7874 0.4064)
			(end -0.7874 -0.4064)
			(stroke
				(width 0.1524)
				(type default)
			)
			(layer "F.SilkS")
		)
		(fp_line
			(start 0.7874 -0.4064)
			(end 0.7874 0.4064)
			(stroke
				(width 0.1524)
				(type default)
			)
			(layer "F.SilkS")
		)
		(fp_line
			(start 0.7874 0.4064)
			(end -0.7874 0.4064)
			(stroke
				(width 0.1524)
				(type default)
			)
			(layer "F.SilkS")
		)
		(fp_line
			(start -0.67945 -0.305054)
			(end -0.12065 -0.305054)
			(stroke
				(width 0.1)
				(type default)
			)
			(layer "F.Fab")
		)
		(fp_line
			(start -0.67945 0.3048)
			(end -0.67945 -0.305054)
			(stroke
				(width 0.1)
				(type default)
			)
			(layer "F.Fab")
		)
		(fp_line
			(start -0.12065 -0.305054)
			(end -0.12065 -0.2794)
			(stroke
				(width 0.1)
				(type default)
			)
			(layer "F.Fab")
		)
		(fp_line
			(start -0.12065 -0.2794)
			(end 0.12065 -0.2794)
			(stroke
				(width 0.1)
				(type default)
			)
			(layer "F.Fab")
		)
		(fp_line
			(start -0.12065 0.2794)
			(end -0.12065 0.3048)
			(stroke
				(width 0.1)
				(type default)
			)
			(layer "F.Fab")
		)
		(fp_line
			(start -0.12065 0.3048)
			(end -0.67945 0.3048)
			(stroke
				(width 0.1)
				(type default)
			)
			(layer "F.Fab")
		)
		(fp_line
			(start 0.120396 0.2794)
			(end -0.12065 0.2794)
			(stroke
				(width 0.1)
				(type default)
			)
			(layer "F.Fab")
		)
		(fp_line
			(start 0.120396 0.3048)
			(end 0.120396 0.2794)
			(stroke
				(width 0.1)
				(type default)
			)
			(layer "F.Fab")
		)
		(fp_line
			(start 0.12065 -0.3048)
			(end 0.67945 -0.3048)
			(stroke
				(width 0.1)
				(type default)
			)
			(layer "F.Fab")
		)
		(fp_line
			(start 0.12065 -0.2794)
			(end 0.12065 -0.3048)
			(stroke
				(width 0.1)
				(type default)
			)
			(layer "F.Fab")
		)
		(fp_line
			(start 0.67945 -0.3048)
			(end 0.67945 0.3048)
			(stroke
				(width 0.1)
				(type default)
			)
			(layer "F.Fab")
		)
		(fp_line
			(start 0.67945 0.3048)
			(end 0.120396 0.3048)
			(stroke
				(width 0.1)
				(type default)
			)
			(layer "F.Fab")
		)
		(pad "1" smd circle
			(at -0.40005 0)
			(size 0 0)
			(layers "F.Cu" "F.Mask" "F.Paste")
			(net "P12V_AUX")
		)
		(pad "2" smd circle
			(at 0.40005 0)
			(size 0 0)
			(layers "F.Cu" "F.Mask" "F.Paste")
			(net "P12V_SCM_UV")
		)
	)
)
